# BASEBOARD_FAB2 (Tioga Pass) — schematic netlist excerpt (pin names and nets, part order shuffled) for the footprints in the layout excerpt that follows; sources: Cadence DE-HDL packaged netlist, KiCad conversion of Wiwynn_Tioga_Pass_MB.brd

CT48  CAP  1000PF 50V 10% X7R  pkg 0402LF  page 219 : A = A_TSENSE_PVDDQ_DEF ; B = GND
C3T8  CAP  10UF 16V 10% X6S  pkg 0805  page 231 : A = VR_FET_SW_P12V_STBY_PVPP_ABC ; B = GND
C9G3  CAP  470PF 50V 10% X7R  pkg 0402LF  page 141 : A = LED_LAN_0_N ; B = GND

(kicad_pcb
	(version 20260206)
	(generator "pcbnew")
	(generator_version "10.0")
	(general
		(thickness 1.6)
		(legacy_teardrops no)
	)
	(paper "A4")
	(title_block
		(title "Wiwynn_Tioga_Pass_MB.brd")
		(comment 1 "Tioga Pass / footprints 3661-3663 of 4770")
	)
	(layers
		(0 "F.Cu" signal "TOP")
		(4 "In1.Cu" signal "L2GND")
		(6 "In2.Cu" signal "L3")
		(8 "In3.Cu" signal "L4GND")
		(10 "In4.Cu" signal "L5")
		(12 "In5.Cu" signal "L6GND")
		(14 "In6.Cu" signal "L7VCC")
		(16 "In7.Cu" signal "L8VCC")
		(18 "In8.Cu" signal "L9GND")
		(20 "In9.Cu" signal "L10")
		(22 "In10.Cu" signal "L11GND")
		(24 "In11.Cu" signal "L12")
		(26 "In12.Cu" signal "L13GND")
		(2 "B.Cu" signal "BOTTOM")
		(9 "F.Adhes" user "F.Adhesive")
		(11 "B.Adhes" user "B.Adhesive")
		(13 "F.Paste" user "Package Geometry/Pastemask Top")
		(15 "B.Paste" user "Package Geometry/Pastemask Bottom")
		(5 "F.SilkS" user "Ref Des/Silkscreen Top")
		(7 "B.SilkS" user "Ref Des/Silkscreen Bottom")
		(1 "F.Mask" user "Board Geometry/Soldermask Top")
		(3 "B.Mask" user "Board Geometry/Soldermask Bottom")
		(17 "Dwgs.User" user "User.Drawings")
		(19 "Cmts.User" user "User.Comments")
		(21 "Eco1.User" user "User.Eco1")
		(23 "Eco2.User" user "User.Eco2")
		(25 "Edge.Cuts" user "Board Geometry/Outline")
		(27 "Margin" user)
		(31 "F.CrtYd" user "Package Geometry/Place Bound Top")
		(29 "B.CrtYd" user "Package Geometry/Place Bound Bottom")
		(35 "F.Fab" user "Ref Des/Assembly Top")
		(33 "B.Fab" user "Ref Des/Assembly Bottom")
	)
	(footprint ""
		(layer "B.Cu")
		(at 483.017322 -17.929606 -90)
		(property "Reference" "C9G3"
			(at 0 0 90)
			(layer "B.SilkS")
			(hide yes)
			(effects
				(font
					(size 1.27 1.27)
				)
				(justify mirror)
			)
		)
		(property "Value" ""
			(at 0 0 90)
			(layer "B.Fab")
			(effects
				(font
					(size 1.27 1.27)
				)
				(justify mirror)
			)
		)
		(duplicate_pad_numbers_are_jumpers no)
		(fp_poly
			(pts
				(xy -0.3048 -0.1016) (xy -0.3048 0.9906) (xy 0.3048 0.9906) (xy 0.3048 -0.1016)
			)
			(stroke
				(width 0)
				(type default)
			)
			(fill no)
			(layer "B.CrtYd")
		)
		(fp_line
			(start -0.3048 0.9906)
			(end -0.3048 -0.1016)
			(stroke
				(width 0.1)
				(type default)
			)
			(layer "B.Fab")
		)
		(fp_line
			(start 0.3048 0.9906)
			(end -0.3048 0.9906)
			(stroke
				(width 0.1)
				(type default)
			)
			(layer "B.Fab")
		)
		(fp_line
			(start -0.3048 -0.1016)
			(end 0.3048 -0.1016)
			(stroke
				(width 0.1)
				(type default)
			)
			(layer "B.Fab")
		)
		(fp_line
			(start 0.3048 -0.1016)
			(end 0.3048 0.9906)
			(stroke
				(width 0.1)
				(type default)
			)
			(layer "B.Fab")
		)
		(pad "1" smd rect
			(at 0 0 90)
			(size 0.508 0.508)
			(layers "B.Cu" "B.Mask" "B.Paste")
			(net "LED_LAN_0_N")
		)
		(pad "2" smd rect
			(at 0 0.889 90)
			(size 0.508 0.508)
			(layers "B.Cu" "B.Mask" "B.Paste")
			(net "GND")
		)
		(zone
			(layer "B.Cu")
			(hatch none 0.5)
			(connect_pads
				(clearance 0)
			)
			(min_thickness 0.25)
			(keepout
				(tracks not_allowed)
				(vias allowed)
				(pads allowed)
				(copperpour not_allowed)
				(footprints allowed)
			)
			(placement
				(enabled no)
				(sheetname "")
			)
			(fill
				(thermal_gap 0.5)
				(thermal_bridge_width 0.5)
				(island_removal_mode 0)
			)
			(polygon
				(pts
					(xy 482.382322 -17.675606) (xy 482.382322 -18.183606) (xy 482.763322 -18.183606) (xy 482.763322 -17.675606)
				)
			)
		)
		(zone
			(layer "B.Cu")
			(hatch none 0.5)
			(connect_pads
				(clearance 0)
			)
			(min_thickness 0.25)
			(keepout
				(tracks allowed)
				(vias not_allowed)
				(pads allowed)
				(copperpour not_allowed)
				(footprints allowed)
			)
			(placement
				(enabled no)
				(sheetname "")
			)
			(fill
				(thermal_gap 0.5)
				(thermal_bridge_width 0.5)
				(island_removal_mode 0)
			)
			(polygon
				(pts
					(xy 482.763322 -17.675606) (xy 482.763322 -18.183606) (xy 482.382322 -18.183606) (xy 482.382322 -17.675606)
				)
			)
		)
	)
	(footprint ""
		(layer "B.Cu")
		(at 350.2914 -145.923 180)
		(property "Reference" "CT48"
			(at 0.8382 -0.84963 180)
			(unlocked yes)
			(layer "B.SilkS")
			(effects
				(font
					(size 0.7874 0.5842)
					(thickness 0.1524)
				)
				(justify left mirror)
			)
		)
		(property "Value" ""
			(at 0 0 0)
			(layer "B.Fab")
			(effects
				(font
					(size 1.27 1.27)
				)
				(justify mirror)
			)
		)
		(duplicate_pad_numbers_are_jumpers no)
		(fp_poly
			(pts
				(xy -0.3048 -0.1016) (xy -0.3048 0.9906) (xy 0.3048 0.9906) (xy 0.3048 -0.1016)
			)
			(stroke
				(width 0)
				(type default)
			)
			(fill no)
			(layer "B.CrtYd")
		)
		(fp_line
			(start 0.3048 0.9906)
			(end -0.3048 0.9906)
			(stroke
				(width 0.1)
				(type default)
			)
			(layer "B.Fab")
		)
		(fp_line
			(start 0.3048 -0.1016)
			(end 0.3048 0.9906)
			(stroke
				(width 0.1)
				(type default)
			)
			(layer "B.Fab")
		)
		(fp_line
			(start -0.3048 0.9906)
			(end -0.3048 -0.1016)
			(stroke
				(width 0.1)
				(type default)
			)
			(layer "B.Fab")
		)
		(fp_line
			(start -0.3048 -0.1016)
			(end 0.3048 -0.1016)
			(stroke
				(width 0.1)
				(type default)
			)
			(layer "B.Fab")
		)
		(pad "1" smd rect
			(at 0 0)
			(size 0.508 0.508)
			(layers "B.Cu" "B.Mask" "B.Paste")
			(net "A_TSENSE_PVDDQ_DEF")
		)
		(pad "2" smd rect
			(at 0 0.889)
			(size 0.508 0.508)
			(layers "B.Cu" "B.Mask" "B.Paste")
			(net "GND")
		)
		(zone
			(layer "B.Cu")
			(hatch none 0.5)
			(connect_pads
				(clearance 0)
			)
			(min_thickness 0.25)
			(keepout
				(tracks not_allowed)
				(vias allowed)
				(pads allowed)
				(copperpour not_allowed)
				(footprints allowed)
			)
			(placement
				(enabled no)
				(sheetname "")
			)
			(fill
				(thermal_gap 0.5)
				(thermal_bridge_width 0.5)
				(island_removal_mode 0)
			)
			(polygon
				(pts
					(xy 350.0374 -146.558) (xy 350.5454 -146.558) (xy 350.5454 -146.177) (xy 350.0374 -146.177)
				)
			)
		)
		(zone
			(layer "B.Cu")
			(hatch none 0.5)
			(connect_pads
				(clearance 0)
			)
			(min_thickness 0.25)
			(keepout
				(tracks allowed)
				(vias not_allowed)
				(pads allowed)
				(copperpour not_allowed)
				(footprints allowed)
			)
			(placement
				(enabled no)
				(sheetname "")
			)
			(fill
				(thermal_gap 0.5)
				(thermal_bridge_width 0.5)
				(island_removal_mode 0)
			)
			(polygon
				(pts
					(xy 350.0374 -146.177) (xy 350.5454 -146.177) (xy 350.5454 -146.558) (xy 350.0374 -146.558)
				)
			)
		)
	)
	(footprint ""
		(layer "B.Cu")
		(at 351.028 -28.575 180)
		(property "Reference" "C3T8"
			(at 0 0 0)
			(layer "B.SilkS")
			(hide yes)
			(effects
				(font
					(size 1.27 1.27)
				)
				(justify mirror)
			)
		)
		(property "Value" ""
			(at 0 0 0)
			(layer "B.Fab")
			(effects
				(font
					(size 1.27 1.27)
				)
				(justify mirror)
			)
		)
		(duplicate_pad_numbers_are_jumpers no)
		(fp_poly
			(pts
				(xy 0.7239 -0.2159) (xy -0.7239 -0.2159) (xy -0.7239 1.9939) (xy 0.7239 1.9939)
			)
			(stroke
				(width 0)
				(type default)
			)
			(fill no)
			(layer "B.CrtYd")
		)
		(fp_line
			(start 0.7239 1.9939)
			(end -0.7239 1.9939)
			(stroke
				(width 0.1)
				(type default)
			)
			(layer "B.Fab")
		)
		(fp_line
			(start 0.7239 -0.2159)
			(end 0.7239 1.9939)
			(stroke
				(width 0.1)
				(type default)
			)
			(layer "B.Fab")
		)
		(fp_line
			(start -0.7239 1.9939)
			(end -0.7239 -0.2159)
			(stroke
				(width 0.1)
				(type default)
			)
			(layer "B.Fab")
		)
		(fp_line
			(start -0.7239 -0.2159)
			(end 0.7239 -0.2159)
			(stroke
				(width 0.1)
				(type default)
			)
			(layer "B.Fab")
		)
		(pad "1" smd rect
			(at 0 0)
			(size 1.27 1.016)
			(layers "B.Cu" "B.Mask" "B.Paste")
			(net "VR_FET_SW_P12V_STBY_PVPP_ABC")
		)
		(pad "2" smd rect
			(at 0 1.778)
			(size 1.27 1.016)
			(layers "B.Cu" "B.Mask" "B.Paste")
			(net "GND")
		)
		(zone
			(layer "B.Cu")
			(hatch none 0.5)
			(connect_pads
				(clearance 0)
			)
			(min_thickness 0.25)
			(keepout
				(tracks not_allowed)
				(vias allowed)
				(pads allowed)
				(copperpour not_allowed)
				(footprints allowed)
			)
			(placement
				(enabled no)
				(sheetname "")
			)
			(fill
				(thermal_gap 0.5)
				(thermal_bridge_width 0.5)
				(island_removal_mode 0)
			)
			(polygon
				(pts
					(xy 350.393 -29.083) (xy 351.663 -29.083) (xy 351.663 -29.845) (xy 350.393 -29.845)
				)
			)
		)
	)
)
